(kicad_pcb
	(version 20241229)
	(generator "pcbnew")
	(generator_version "9.0")
	(general
		(thickness 1.711)
		(legacy_teardrops no)
	)
	(paper "A4")
	(title_block
		(title "Antmicro Baseboard for Jetson AGX Thor")
		(date "2026-02-18")
		(rev "1.1.0")
		(company "Antmicro Ltd")
		(comment 1 "www.antmicro.com")
		(comment 9 "footprints 689-694 of 1170")
	)
	(layers
		(0 "F.Cu" signal)
		(4 "In1.Cu" signal)
		(6 "In2.Cu" signal)
		(8 "In3.Cu" signal)
		(10 "In4.Cu" jumper)
		(12 "In5.Cu" signal)
		(14 "In6.Cu" signal)
		(16 "In7.Cu" signal)
		(18 "In8.Cu" signal)
		(2 "B.Cu" signal)
		(9 "F.Adhes" user "F.Adhesive")
		(11 "B.Adhes" user "B.Adhesive")
		(13 "F.Paste" user)
		(15 "B.Paste" user)
		(5 "F.SilkS" user "F.Silkscreen")
		(7 "B.SilkS" user "B.Silkscreen")
		(1 "F.Mask" user)
		(3 "B.Mask" user)
		(17 "Dwgs.User" user "User.Drawings")
		(19 "Cmts.User" user "User.Comments")
		(21 "Eco1.User" user "User.Eco1")
		(23 "Eco2.User" user "User.Eco2")
		(25 "Edge.Cuts" user)
		(27 "Margin" user)
		(31 "F.CrtYd" user "F.Courtyard")
		(29 "B.CrtYd" user "B.Courtyard")
		(35 "F.Fab" user)
		(33 "B.Fab" user)
	)
	(footprint "antmicro-footprints:R_0402_1005Metric"
		(layer "B.Cu")
		(at 170.75 57.5 -90)
		(descr "Resistor SMD 0402")
		(tags "resistor SMD 0402")
		(property "Reference" "R64"
			(at -3.58 -0.365532 90)
			(layer "B.SilkS")
			(effects
				(font
					(size 0.7 0.7)
					(thickness 0.15)
				)
				(justify left bottom mirror)
			)
		)
		(property "Value" "R_470R_0402"
			(at -1.011843 -1.772047 90)
			(layer "B.Fab")
			(effects
				(font
					(size 0.7 0.7)
					(thickness 0.15)
				)
				(justify left bottom mirror)
			)
		)
		(property "Datasheet" "https://www.bourns.com/docs/product-datasheets/cr.pdf"
			(at 0 0 90)
			(layer "B.Fab")
			(hide yes)
			(effects
				(font
					(size 1.27 1.27)
					(thickness 0.15)
				)
				(justify mirror)
			)
		)
		(property "Description" "SMD Chip Resistor, 470 ohm, ± 1%, 62.5 mW, 0402 [1005 Metric], Thick Film, General Purpose"
			(at 0 0 90)
			(layer "B.Fab")
			(hide yes)
			(effects
				(font
					(size 1.27 1.27)
					(thickness 0.15)
				)
				(justify mirror)
			)
		)
		(property "MPN" "CR0402-FX-4700GLF"
			(at 0 0 90)
			(unlocked yes)
			(layer "B.Fab")
			(hide yes)
			(effects
				(font
					(size 1 1)
					(thickness 0.15)
				)
				(justify mirror)
			)
		)
		(property "Manufacturer" "Bourns"
			(at 0 0 90)
			(unlocked yes)
			(layer "B.Fab")
			(hide yes)
			(effects
				(font
					(size 1 1)
					(thickness 0.15)
				)
				(justify mirror)
			)
		)
		(property "License" "Apache-2.0"
			(at 0 0 90)
			(unlocked yes)
			(layer "B.Fab")
			(hide yes)
			(effects
				(font
					(size 1 1)
					(thickness 0.15)
				)
				(justify mirror)
			)
		)
		(property "Author" "Antmicro"
			(at 0 0 90)
			(unlocked yes)
			(layer "B.Fab")
			(hide yes)
			(effects
				(font
					(size 1 1)
					(thickness 0.15)
				)
				(justify mirror)
			)
		)
		(property "Val" "470R"
			(at 0 0 90)
			(unlocked yes)
			(layer "B.Fab")
			(hide yes)
			(effects
				(font
					(size 1 1)
					(thickness 0.15)
				)
				(justify mirror)
			)
		)
		(property "Tolerance" "1%"
			(at 0 0 90)
			(unlocked yes)
			(layer "B.Fab")
			(hide yes)
			(effects
				(font
					(size 1 1)
					(thickness 0.15)
				)
				(justify mirror)
			)
		)
		(sheetname "/Power/")
		(sheetfile "power.kicad_sch")
		(attr smd)
		(fp_rect
			(start -0.925 0.47)
			(end 0.925 -0.47)
			(stroke
				(width 0.05)
				(type default)
			)
			(fill no)
			(layer "B.CrtYd")
		)
		(fp_rect
			(start -0.5 0.25)
			(end 0.5 -0.25)
			(stroke
				(width 0.15)
				(type solid)
			)
			(fill no)
			(layer "B.Fab")
		)
		(fp_text user "License: Apache-2.0"
			(at -0.95 -5.169 90)
			(layer "B.Fab")
			(effects
				(font
					(size 0.7 0.7)
					(thickness 0.15)
				)
				(justify left bottom mirror)
			)
		)
		(fp_text user "${REFERENCE}"
			(at -0.95 -3.168 90)
			(layer "B.Fab")
			(effects
				(font
					(size 0.7 0.7)
					(thickness 0.15)
				)
				(justify left bottom mirror)
			)
		)
		(fp_text user "Author: Antmicro"
			(at -0.95 -4.169 90)
			(layer "B.Fab")
			(effects
				(font
					(size 0.7 0.7)
					(thickness 0.15)
				)
				(justify left bottom mirror)
			)
		)
		(pad "1" smd roundrect
			(at -0.48 0 270)
			(size 0.59 0.64)
			(layers "B.Cu" "B.Mask" "B.Paste")
			(roundrect_rratio 0.25)
			(net 490 "Net-(D12-A)")
			(pintype "passive")
		)
		(pad "2" smd roundrect
			(at 0.48 0 270)
			(size 0.59 0.64)
			(layers "B.Cu" "B.Mask" "B.Paste")
			(roundrect_rratio 0.25)
			(net 5 "+5V")
			(pintype "passive")
		)
	)
	(footprint "antmicro-footprints:TP_SMD_0.75mm"
		(layer "B.Cu")
		(at 183.14 58 180)
		(property "Reference" "TP127"
			(at -0.43 4.04 90)
			(layer "B.SilkS")
			(effects
				(font
					(size 0.7 0.7)
					(thickness 0.15)
				)
				(justify left bottom mirror)
			)
		)
		(property "Value" "TP_0.75mm_SMD"
			(at 0 -1.2 0)
			(layer "B.Fab")
			(effects
				(font
					(size 0.7 0.7)
					(thickness 0.15)
				)
				(justify left bottom mirror)
			)
		)
		(property "Description" "SMT test point"
			(at 0 0 0)
			(layer "B.Fab")
			(hide yes)
			(effects
				(font
					(size 1.27 1.27)
					(thickness 0.15)
				)
				(justify mirror)
			)
		)
		(property "MPN" ""
			(at 0 0 0)
			(unlocked yes)
			(layer "B.Fab")
			(hide yes)
			(effects
				(font
					(size 1 1)
					(thickness 0.15)
				)
				(justify mirror)
			)
		)
		(property "Manufacturer" ""
			(at 0 0 0)
			(unlocked yes)
			(layer "B.Fab")
			(hide yes)
			(effects
				(font
					(size 1 1)
					(thickness 0.15)
				)
				(justify mirror)
			)
		)
		(property "Author" "Antmicro"
			(at 0 0 0)
			(unlocked yes)
			(layer "B.Fab")
			(hide yes)
			(effects
				(font
					(size 1 1)
					(thickness 0.15)
				)
				(justify mirror)
			)
		)
		(property "License" "Apache-2.0"
			(at 0 0 0)
			(unlocked yes)
			(layer "B.Fab")
			(hide yes)
			(effects
				(font
					(size 1 1)
					(thickness 0.15)
				)
				(justify mirror)
			)
		)
		(sheetname "/Power/")
		(sheetfile "power.kicad_sch")
		(attr exclude_from_pos_files exclude_from_bom)
		(fp_circle
			(center 0 0)
			(end 0.475 0)
			(stroke
				(width 0.05)
				(type default)
			)
			(fill no)
			(layer "B.CrtYd")
		)
		(fp_text user "License: Apache-2.0"
			(at -0.4 -5.101 0)
			(layer "B.Fab")
			(effects
				(font
					(size 0.7 0.7)
					(thickness 0.15)
				)
				(justify left bottom mirror)
			)
		)
		(fp_text user "${REFERENCE}"
			(at -0.4 -2.7 0)
			(layer "B.Fab")
			(effects
				(font
					(size 0.7 0.7)
					(thickness 0.15)
				)
				(justify left bottom mirror)
			)
		)
		(fp_text user "Author: Antmicro"
			(at -0.4 -3.901 0)
			(layer "B.Fab")
			(effects
				(font
					(size 0.7 0.7)
					(thickness 0.15)
				)
				(justify left bottom mirror)
			)
		)
		(pad "1" smd circle
			(at 0 0 180)
			(size 0.75 0.75)
			(layers "B.Cu" "B.Mask")
			(net 904 "+20V")
			(pinfunction "1")
			(pintype "passive")
		)
	)
	(footprint "antmicro-footprints:TP_SMD_0.75mm"
		(layer "B.Cu")
		(at 63 76.6 -90)
		(property "Reference" "TP113"
			(at 0.4 -0.4 90)
			(layer "B.SilkS")
			(effects
				(font
					(size 0.7 0.7)
					(thickness 0.15)
				)
				(justify left bottom mirror)
			)
		)
		(property "Value" "TP_0.75mm_SMD"
			(at 0 -1.2 90)
			(layer "B.Fab")
			(effects
				(font
					(size 0.7 0.7)
					(thickness 0.15)
				)
				(justify left bottom mirror)
			)
		)
		(property "Description" "SMT test point"
			(at 0 0 90)
			(layer "B.Fab")
			(hide yes)
			(effects
				(font
					(size 1.27 1.27)
					(thickness 0.15)
				)
				(justify mirror)
			)
		)
		(property "MPN" ""
			(at 0 0 90)
			(unlocked yes)
			(layer "B.Fab")
			(hide yes)
			(effects
				(font
					(size 1 1)
					(thickness 0.15)
				)
				(justify mirror)
			)
		)
		(property "Manufacturer" ""
			(at 0 0 90)
			(unlocked yes)
			(layer "B.Fab")
			(hide yes)
			(effects
				(font
					(size 1 1)
					(thickness 0.15)
				)
				(justify mirror)
			)
		)
		(property "Author" "Antmicro"
			(at 0 0 90)
			(unlocked yes)
			(layer "B.Fab")
			(hide yes)
			(effects
				(font
					(size 1 1)
					(thickness 0.15)
				)
				(justify mirror)
			)
		)
		(property "License" "Apache-2.0"
			(at 0 0 90)
			(unlocked yes)
			(layer "B.Fab")
			(hide yes)
			(effects
				(font
					(size 1 1)
					(thickness 0.15)
				)
				(justify mirror)
			)
		)
		(sheetname "/Expansion connector/")
		(sheetfile "expansion_connector.kicad_sch")
		(attr exclude_from_pos_files exclude_from_bom)
		(fp_circle
			(center 0 0)
			(end 0.475 0)
			(stroke
				(width 0.05)
				(type default)
			)
			(fill no)
			(layer "B.CrtYd")
		)
		(fp_text user "License: Apache-2.0"
			(at -0.4 -5.101 90)
			(layer "B.Fab")
			(effects
				(font
					(size 0.7 0.7)
					(thickness 0.15)
				)
				(justify left bottom mirror)
			)
		)
		(fp_text user "Author: Antmicro"
			(at -0.4 -3.901 90)
			(layer "B.Fab")
			(effects
				(font
					(size 0.7 0.7)
					(thickness 0.15)
				)
				(justify left bottom mirror)
			)
		)
		(fp_text user "${REFERENCE}"
			(at -0.4 -2.7 90)
			(layer "B.Fab")
			(effects
				(font
					(size 0.7 0.7)
					(thickness 0.15)
				)
				(justify left bottom mirror)
			)
		)
		(pad "1" smd circle
			(at 0 0 270)
			(size 0.75 0.75)
			(layers "B.Cu" "B.Mask")
			(net 717 "Net-(J18-PadL01)")
			(pinfunction "1")
			(pintype "passive")
		)
	)
	(footprint "antmicro-footprints:R_0402_1005Metric"
		(layer "B.Cu")
		(at 236.689002 93.424001)
		(descr "Resistor SMD 0402")
		(tags "resistor SMD 0402")
		(property "Reference" "R144"
			(at -2.689002 -2.624001 0)
			(layer "B.SilkS")
			(effects
				(font
					(size 0.7 0.7)
					(thickness 0.15)
				)
				(justify right top mirror)
			)
		)
		(property "Value" "R_10k_0402"
			(at -1.011843 -1.772046 0)
			(layer "B.Fab")
			(effects
				(font
					(size 0.7 0.7)
					(thickness 0.15)
				)
				(justify right top mirror)
			)
		)
		(property "Datasheet" "https://www.bourns.com/docs/product-datasheets/cr.pdf"
			(at 0 0 0)
			(layer "B.Fab")
			(hide yes)
			(effects
				(font
					(size 1.27 1.27)
					(thickness 0.15)
				)
				(justify mirror)
			)
		)
		(property "Description" "SMD Chip Resistor, 10 kohm, ± 1%, 62.5 mW, 0402 [1005 Metric], Thick Film, General Purpose"
			(at 0 0 0)
			(layer "B.Fab")
			(hide yes)
			(effects
				(font
					(size 1.27 1.27)
					(thickness 0.15)
				)
				(justify mirror)
			)
		)
		(property "Manufacturer" "Bourns"
			(at 0 0 180)
			(unlocked yes)
			(layer "B.Fab")
			(hide yes)
			(effects
				(font
					(size 1 1)
					(thickness 0.15)
				)
				(justify mirror)
			)
		)
		(property "MPN" "CR0402-FX-1002GLF"
			(at 0 0 180)
			(unlocked yes)
			(layer "B.Fab")
			(hide yes)
			(effects
				(font
					(size 1 1)
					(thickness 0.15)
				)
				(justify mirror)
			)
		)
		(property "Val" "10k"
			(at 0 0 180)
			(unlocked yes)
			(layer "B.Fab")
			(hide yes)
			(effects
				(font
					(size 1 1)
					(thickness 0.15)
				)
				(justify mirror)
			)
		)
		(property "License" "Apache-2.0"
			(at 0 0 180)
			(unlocked yes)
			(layer "B.Fab")
			(hide yes)
			(effects
				(font
					(size 1 1)
					(thickness 0.15)
				)
				(justify mirror)
			)
		)
		(property "Author" "Antmicro"
			(at 0 0 180)
			(unlocked yes)
			(layer "B.Fab")
			(hide yes)
			(effects
				(font
					(size 1 1)
					(thickness 0.15)
				)
				(justify mirror)
			)
		)
		(property "Tolerance" "1%"
			(at 0 0 180)
			(unlocked yes)
			(layer "B.Fab")
			(hide yes)
			(effects
				(font
					(size 1 1)
					(thickness 0.15)
				)
				(justify mirror)
			)
		)
		(sheetname "/USB DP Alt mode/")
		(sheetfile "usb_dp.kicad_sch")
		(attr smd)
		(fp_poly
			(pts
				(xy -0.925 0.47) (xy -0.925 -0.47) (xy 0.925 -0.47) (xy 0.925 0.47)
			)
			(stroke
				(width 0.05)
				(type default)
			)
			(fill no)
			(layer "B.CrtYd")
		)
		(fp_poly
			(pts
				(xy -0.5 0.25) (xy -0.5 -0.25) (xy 0.5 -0.25) (xy 0.5 0.25)
			)
			(stroke
				(width 0.15)
				(type solid)
			)
			(fill no)
			(layer "B.Fab")
		)
		(fp_text user "Author: Antmicro"
			(at -0.95 -4.169 0)
			(layer "B.Fab")
			(effects
				(font
					(size 0.7 0.7)
					(thickness 0.15)
				)
				(justify right top mirror)
			)
		)
		(fp_text user "License: Apache-2.0"
			(at -0.949999 -5.169 0)
			(layer "B.Fab")
			(effects
				(font
					(size 0.7 0.7)
					(thickness 0.15)
				)
				(justify right top mirror)
			)
		)
		(fp_text user "${REFERENCE}"
			(at -0.95 -3.168 0)
			(layer "B.Fab")
			(effects
				(font
					(size 0.7 0.7)
					(thickness 0.15)
				)
				(justify right top mirror)
			)
		)
		(pad "1" smd roundrect
			(at -0.48 0)
			(size 0.59 0.64)
			(layers "B.Cu" "B.Mask" "B.Paste")
			(roundrect_rratio 0.25)
			(net 1 "GND")
			(pintype "passive")
		)
		(pad "2" smd roundrect
			(at 0.48 0)
			(size 0.59 0.64)
			(layers "B.Cu" "B.Mask" "B.Paste")
			(roundrect_rratio 0.25)
			(net 971 "Net-(U35-EN)")
			(pintype "passive")
		)
	)
	(footprint "antmicro-footprints:R_0402_1005Metric"
		(layer "B.Cu")
		(at 124.6 131.85)
		(descr "Resistor SMD 0402")
		(tags "resistor SMD 0402")
		(property "Reference" "R203"
			(at -1.19 -5.32 0)
			(layer "B.SilkS")
			(effects
				(font
					(size 0.7 0.7)
					(thickness 0.15)
				)
				(justify right top mirror)
			)
		)
		(property "Value" "R_47k_0402"
			(at -1.011843 -1.772046 0)
			(layer "B.Fab")
			(effects
				(font
					(size 0.7 0.7)
					(thickness 0.15)
				)
				(justify right top mirror)
			)
		)
		(property "Datasheet" "https://www.bourns.com/docs/product-datasheets/cr.pdf"
			(at 0 0 0)
			(layer "B.Fab")
			(hide yes)
			(effects
				(font
					(size 1.27 1.27)
					(thickness 0.15)
				)
				(justify mirror)
			)
		)
		(property "Description" "SMD Chip Resistor, 47 kohm, ± 1%, 62.5 mW, 0402 [1005 Metric], Thick Film, General Purpose"
			(at 0 0 0)
			(layer "B.Fab")
			(hide yes)
			(effects
				(font
					(size 1.27 1.27)
					(thickness 0.15)
				)
				(justify mirror)
			)
		)
		(property "MPN" "CR0402-FX-4702GLF"
			(at 0 0 180)
			(unlocked yes)
			(layer "B.Fab")
			(hide yes)
			(effects
				(font
					(size 1 1)
					(thickness 0.15)
				)
				(justify mirror)
			)
		)
		(property "Manufacturer" "Bourns"
			(at 0 0 180)
			(unlocked yes)
			(layer "B.Fab")
			(hide yes)
			(effects
				(font
					(size 1 1)
					(thickness 0.15)
				)
				(justify mirror)
			)
		)
		(property "License" "Apache-2.0"
			(at 0 0 180)
			(unlocked yes)
			(layer "B.Fab")
			(hide yes)
			(effects
				(font
					(size 1 1)
					(thickness 0.15)
				)
				(justify mirror)
			)
		)
		(property "Author" "Antmicro"
			(at 0 0 180)
			(unlocked yes)
			(layer "B.Fab")
			(hide yes)
			(effects
				(font
					(size 1 1)
					(thickness 0.15)
				)
				(justify mirror)
			)
		)
		(property "Val" "47k"
			(at 0 0 180)
			(unlocked yes)
			(layer "B.Fab")
			(hide yes)
			(effects
				(font
					(size 1 1)
					(thickness 0.15)
				)
				(justify mirror)
			)
		)
		(property "Tolerance" "1%"
			(at 0 0 180)
			(unlocked yes)
			(layer "B.Fab")
			(hide yes)
			(effects
				(font
					(size 1 1)
					(thickness 0.15)
				)
				(justify mirror)
			)
		)
		(sheetname "/M.2/")
		(sheetfile "m2.kicad_sch")
		(attr smd)
		(fp_poly
			(pts
				(xy -0.925 0.47) (xy 0.925 0.47) (xy 0.925 -0.47) (xy -0.925 -0.47)
			)
			(stroke
				(width 0.05)
				(type default)
			)
			(fill no)
			(layer "B.CrtYd")
		)
		(fp_poly
			(pts
				(xy -0.5 0.25) (xy 0.5 0.25) (xy 0.5 -0.25) (xy -0.5 -0.25)
			)
			(stroke
				(width 0.15)
				(type solid)
			)
			(fill no)
			(layer "B.Fab")
		)
		(fp_text user "License: Apache-2.0"
			(at -0.949999 -5.169 0)
			(layer "B.Fab")
			(effects
				(font
					(size 0.7 0.7)
					(thickness 0.15)
				)
				(justify right top mirror)
			)
		)
		(fp_text user "${REFERENCE}"
			(at -0.95 -3.168 0)
			(layer "B.Fab")
			(effects
				(font
					(size 0.7 0.7)
					(thickness 0.15)
				)
				(justify right top mirror)
			)
		)
		(fp_text user "Author: Antmicro"
			(at -0.95 -4.169 0)
			(layer "B.Fab")
			(effects
				(font
					(size 0.7 0.7)
					(thickness 0.15)
				)
				(justify right top mirror)
			)
		)
		(pad "1" smd roundrect
			(at -0.48 0)
			(size 0.59 0.64)
			(layers "B.Cu" "B.Mask" "B.Paste")
			(roundrect_rratio 0.25)
			(net 831 "/M.2/~{PERST_E}")
			(pintype "passive")
		)
		(pad "2" smd roundrect
			(at 0.48 0)
			(size 0.59 0.64)
			(layers "B.Cu" "B.Mask" "B.Paste")
			(roundrect_rratio 0.25)
			(net 2 "+3V3")
			(pintype "passive")
		)
	)
	(footprint "antmicro-footprints:TP_SMD_0.75mm"
		(layer "B.Cu")
		(at 120.51 72.11 90)
		(property "Reference" "TP56"
			(at -2.79 0.79 90)
			(layer "B.SilkS")
			(effects
				(font
					(size 0.7 0.7)
					(thickness 0.15)
				)
				(justify right top mirror)
			)
		)
		(property "Value" "TP_0.75mm_SMD"
			(at 0 -1.2 90)
			(layer "B.Fab")
			(effects
				(font
					(size 0.7 0.7)
					(thickness 0.15)
				)
				(justify right top mirror)
			)
		)
		(property "Description" "SMT test point"
			(at 0 0 90)
			(layer "B.Fab")
			(hide yes)
			(effects
				(font
					(size 1.27 1.27)
					(thickness 0.15)
				)
				(justify mirror)
			)
		)
		(property "MPN" ""
			(at 0 0 270)
			(unlocked yes)
			(layer "B.Fab")
			(hide yes)
			(effects
				(font
					(size 1 1)
					(thickness 0.15)
				)
				(justify mirror)
			)
		)
		(property "Manufacturer" ""
			(at 0 0 270)
			(unlocked yes)
			(layer "B.Fab")
			(hide yes)
			(effects
				(font
					(size 1 1)
					(thickness 0.15)
				)
				(justify mirror)
			)
		)
		(property "Author" "Antmicro"
			(at 0 0 270)
			(unlocked yes)
			(layer "B.Fab")
			(hide yes)
			(effects
				(font
					(size 1 1)
					(thickness 0.15)
				)
				(justify mirror)
			)
		)
		(property "License" "Apache-2.0"
			(at 0 0 270)
			(unlocked yes)
			(layer "B.Fab")
			(hide yes)
			(effects
				(font
					(size 1 1)
					(thickness 0.15)
				)
				(justify mirror)
			)
		)
		(sheetname "/SoM_Power/")
		(sheetfile "som_power.kicad_sch")
		(attr exclude_from_pos_files exclude_from_bom)
		(fp_circle
			(center 0 0)
			(end 0.475 0)
			(stroke
				(width 0.05)
				(type default)
			)
			(fill no)
			(layer "B.CrtYd")
		)
		(fp_text user "License: Apache-2.0"
			(at -0.4 -5.101 90)
			(layer "B.Fab")
			(effects
				(font
					(size 0.7 0.7)
					(thickness 0.15)
				)
				(justify right top mirror)
			)
		)
		(fp_text user "${REFERENCE}"
			(at -0.4 -2.7 90)
			(layer "B.Fab")
			(effects
				(font
					(size 0.7 0.7)
					(thickness 0.15)
				)
				(justify right top mirror)
			)
		)
		(fp_text user "Author: Antmicro"
			(at -0.4 -3.901 90)
			(layer "B.Fab")
			(effects
				(font
					(size 0.7 0.7)
					(thickness 0.15)
				)
				(justify right top mirror)
			)
		)
		(pad "1" smd circle
			(at 0 0 90)
			(size 0.75 0.75)
			(layers "B.Cu" "B.Mask")
			(net 875 "Net-(J1A-FSI_GPIO03)")
			(pinfunction "1")
			(pintype "passive")
		)
	)
)
